# S9S_MB_2U (Grand Teton) — schematic netlist excerpt (pin names and nets, part order shuffled) for the footprints in the layout excerpt that follows; sources: Cadence DE-HDL packaged netlist, KiCad conversion of 03242023_DA0F0TMBIJ0_F0T_Motherboard_J_brd_V01_OCP.brd

R736  Q_RES  1K 1% EMPTY  pkg 0402LF  page 220 : A = FM_DIMM_12V_CPS_SX_N ; B = GND
C1578  Q_CAP_DIFFBUS  DIFF BUS_0.22UF 6.3V 20% X6S  pkg C0201  page 175 : \1\ = P5E_CPU0_PE4_TX_C_DN<0> ; \2\ = P5E_CPU0_PE4_TX_DN<0>
R4618  Q_RES  33.2 1% CHIP  pkg 0402LF  page 158 : A = HP_LVC3_OCP_V3_1_PWRGD ; B = HP_LVC3_OCP_V3_1_PWRGD_R

(kicad_pcb
	(version 20260206)
	(generator "pcbnew")
	(generator_version "10.0")
	(general
		(thickness 1.6)
		(legacy_teardrops no)
	)
	(paper "A4")
	(title_block
		(title "03242023_DA0F0TMBIJ0_F0T_Motherboard_J_brd_V01_OCP.brd")
		(comment 1 "Grand Teton / footprints 3887-3889 of 6105")
	)
	(layers
		(0 "F.Cu" signal "TOP")
		(4 "In1.Cu" signal "GND")
		(6 "In2.Cu" signal "IN1")
		(8 "In3.Cu" signal "GND1")
		(10 "In4.Cu" signal "IN2")
		(12 "In5.Cu" signal "GND2")
		(14 "In6.Cu" signal "IN3")
		(16 "In7.Cu" signal "GND3")
		(18 "In8.Cu" signal "VCC")
		(20 "In9.Cu" signal "VCC1")
		(22 "In10.Cu" signal "GND4")
		(24 "In11.Cu" signal "IN4")
		(26 "In12.Cu" signal "GND5")
		(28 "In13.Cu" signal "IN5")
		(30 "In14.Cu" signal "GND6")
		(32 "In15.Cu" signal "IN6")
		(34 "In16.Cu" signal "GND7")
		(2 "B.Cu" signal "BOTTOM")
		(9 "F.Adhes" user "F.Adhesive")
		(11 "B.Adhes" user "B.Adhesive")
		(13 "F.Paste" user "Package Geometry/Pastemask Top")
		(15 "B.Paste" user "Package Geometry/Pastemask Bottom")
		(5 "F.SilkS" user "Ref Des/Silkscreen Top")
		(7 "B.SilkS" user "Ref Des/Silkscreen Bottom")
		(1 "F.Mask" user "Board Geometry/Soldermask Top")
		(3 "B.Mask" user "Board Geometry/Soldermask Bottom")
		(17 "Dwgs.User" user "User.Drawings")
		(19 "Cmts.User" user "User.Comments")
		(21 "Eco1.User" user "User.Eco1")
		(23 "Eco2.User" user "User.Eco2")
		(25 "Edge.Cuts" user "Board Geometry/Outline")
		(27 "Margin" user)
		(31 "F.CrtYd" user "Package Geometry/Place Bound Top")
		(29 "B.CrtYd" user "Package Geometry/Place Bound Bottom")
		(35 "F.Fab" user "Ref Des/Assembly Top")
		(33 "B.Fab" user "Ref Des/Assembly Bottom")
	)
	(footprint ""
		(layer "F.Cu")
		(at 201.00036 -120.614948)
		(property "Reference" "R736"
			(at 0 0 0)
			(layer "F.SilkS")
			(hide yes)
			(effects
				(font
					(size 1.27 1.27)
				)
			)
		)
		(property "Value" ""
			(at 0 0 0)
			(layer "F.Fab")
			(effects
				(font
					(size 1.27 1.27)
				)
			)
		)
		(duplicate_pad_numbers_are_jumpers no)
		(fp_line
			(start -0.7874 -0.4064)
			(end 0.7874 -0.4064)
			(stroke
				(width 0.1524)
				(type default)
			)
			(layer "F.SilkS")
		)
		(fp_line
			(start -0.7874 0.4064)
			(end -0.7874 -0.4064)
			(stroke
				(width 0.1524)
				(type default)
			)
			(layer "F.SilkS")
		)
		(fp_line
			(start 0.7874 -0.4064)
			(end 0.7874 0.4064)
			(stroke
				(width 0.1524)
				(type default)
			)
			(layer "F.SilkS")
		)
		(fp_line
			(start 0.7874 0.4064)
			(end -0.7874 0.4064)
			(stroke
				(width 0.1524)
				(type default)
			)
			(layer "F.SilkS")
		)
		(fp_line
			(start -0.67945 -0.305054)
			(end -0.12065 -0.305054)
			(stroke
				(width 0.1)
				(type default)
			)
			(layer "F.Fab")
		)
		(fp_line
			(start -0.67945 0.3048)
			(end -0.67945 -0.305054)
			(stroke
				(width 0.1)
				(type default)
			)
			(layer "F.Fab")
		)
		(fp_line
			(start -0.12065 -0.305054)
			(end -0.12065 -0.2794)
			(stroke
				(width 0.1)
				(type default)
			)
			(layer "F.Fab")
		)
		(fp_line
			(start -0.12065 -0.2794)
			(end 0.12065 -0.2794)
			(stroke
				(width 0.1)
				(type default)
			)
			(layer "F.Fab")
		)
		(fp_line
			(start -0.12065 0.2794)
			(end -0.12065 0.3048)
			(stroke
				(width 0.1)
				(type default)
			)
			(layer "F.Fab")
		)
		(fp_line
			(start -0.12065 0.3048)
			(end -0.67945 0.3048)
			(stroke
				(width 0.1)
				(type default)
			)
			(layer "F.Fab")
		)
		(fp_line
			(start 0.120396 0.2794)
			(end -0.12065 0.2794)
			(stroke
				(width 0.1)
				(type default)
			)
			(layer "F.Fab")
		)
		(fp_line
			(start 0.120396 0.3048)
			(end 0.120396 0.2794)
			(stroke
				(width 0.1)
				(type default)
			)
			(layer "F.Fab")
		)
		(fp_line
			(start 0.12065 -0.3048)
			(end 0.67945 -0.3048)
			(stroke
				(width 0.1)
				(type default)
			)
			(layer "F.Fab")
		)
		(fp_line
			(start 0.12065 -0.2794)
			(end 0.12065 -0.3048)
			(stroke
				(width 0.1)
				(type default)
			)
			(layer "F.Fab")
		)
		(fp_line
			(start 0.67945 -0.3048)
			(end 0.67945 0.3048)
			(stroke
				(width 0.1)
				(type default)
			)
			(layer "F.Fab")
		)
		(fp_line
			(start 0.67945 0.3048)
			(end 0.120396 0.3048)
			(stroke
				(width 0.1)
				(type default)
			)
			(layer "F.Fab")
		)
		(pad "1" smd circle
			(at -0.40005 0)
			(size 0 0)
			(layers "F.Cu" "F.Mask" "F.Paste")
			(net "FM_DIMM_12V_CPS_SX_N")
		)
		(pad "2" smd circle
			(at 0.40005 0)
			(size 0 0)
			(layers "F.Cu" "F.Mask" "F.Paste")
			(net "GND")
		)
	)
	(footprint ""
		(layer "F.Cu")
		(at 303.954688 -402.371052 -90)
		(property "Reference" "C1578"
			(at 0 0 270)
			(layer "F.SilkS")
			(hide yes)
			(effects
				(font
					(size 1.27 1.27)
				)
			)
		)
		(property "Value" ""
			(at 0 0 270)
			(layer "F.Fab")
			(effects
				(font
					(size 1.27 1.27)
				)
			)
		)
		(duplicate_pad_numbers_are_jumpers no)
		(fp_line
			(start -0.299974 0.150114)
			(end -0.299974 -0.150114)
			(stroke
				(width 0.1)
				(type default)
			)
			(layer "F.Fab")
		)
		(fp_line
			(start 0.299974 0.150114)
			(end -0.299974 0.150114)
			(stroke
				(width 0.1)
				(type default)
			)
			(layer "F.Fab")
		)
		(fp_line
			(start -0.299974 -0.150114)
			(end 0.299974 -0.150114)
			(stroke
				(width 0.1)
				(type default)
			)
			(layer "F.Fab")
		)
		(fp_line
			(start 0.299974 -0.150114)
			(end 0.299974 0.150114)
			(stroke
				(width 0.1)
				(type default)
			)
			(layer "F.Fab")
		)
		(pad "1" smd rect
			(at -0.2667 0 270)
			(size 0.3048 0.381)
			(layers "F.Cu" "F.Mask" "F.Paste")
			(net "P5E_CPU0_PE4_TX_C_DN<0>")
		)
		(pad "2" smd rect
			(at 0.2667 0 270)
			(size 0.3048 0.381)
			(layers "F.Cu" "F.Mask" "F.Paste")
			(net "P5E_CPU0_PE4_TX_DN<0>")
		)
	)
	(footprint ""
		(layer "F.Cu")
		(at 385.318 -34.585148)
		(property "Reference" "R4618"
			(at 0 0 0)
			(layer "F.SilkS")
			(hide yes)
			(effects
				(font
					(size 1.27 1.27)
				)
			)
		)
		(property "Value" ""
			(at 0 0 0)
			(layer "F.Fab")
			(effects
				(font
					(size 1.27 1.27)
				)
			)
		)
		(duplicate_pad_numbers_are_jumpers no)
		(fp_line
			(start -0.7874 -0.4064)
			(end 0.7874 -0.4064)
			(stroke
				(width 0.1524)
				(type default)
			)
			(layer "F.SilkS")
		)
		(fp_line
			(start -0.7874 0.4064)
			(end -0.7874 -0.4064)
			(stroke
				(width 0.1524)
				(type default)
			)
			(layer "F.SilkS")
		)
		(fp_line
			(start 0.7874 -0.4064)
			(end 0.7874 0.4064)
			(stroke
				(width 0.1524)
				(type default)
			)
			(layer "F.SilkS")
		)
		(fp_line
			(start 0.7874 0.4064)
			(end -0.7874 0.4064)
			(stroke
				(width 0.1524)
				(type default)
			)
			(layer "F.SilkS")
		)
		(fp_line
			(start -0.67945 -0.305054)
			(end -0.12065 -0.305054)
			(stroke
				(width 0.1)
				(type default)
			)
			(layer "F.Fab")
		)
		(fp_line
			(start -0.67945 0.3048)
			(end -0.67945 -0.305054)
			(stroke
				(width 0.1)
				(type default)
			)
			(layer "F.Fab")
		)
		(fp_line
			(start -0.12065 -0.305054)
			(end -0.12065 -0.2794)
			(stroke
				(width 0.1)
				(type default)
			)
			(layer "F.Fab")
		)
		(fp_line
			(start -0.12065 -0.2794)
			(end 0.12065 -0.2794)
			(stroke
				(width 0.1)
				(type default)
			)
			(layer "F.Fab")
		)
		(fp_line
			(start -0.12065 0.2794)
			(end -0.12065 0.3048)
			(stroke
				(width 0.1)
				(type default)
			)
			(layer "F.Fab")
		)
		(fp_line
			(start -0.12065 0.3048)
			(end -0.67945 0.3048)
			(stroke
				(width 0.1)
				(type default)
			)
			(layer "F.Fab")
		)
		(fp_line
			(start 0.120396 0.2794)
			(end -0.12065 0.2794)
			(stroke
				(width 0.1)
				(type default)
			)
			(layer "F.Fab")
		)
		(fp_line
			(start 0.120396 0.3048)
			(end 0.120396 0.2794)
			(stroke
				(width 0.1)
				(type default)
			)
			(layer "F.Fab")
		)
		(fp_line
			(start 0.12065 -0.3048)
			(end 0.67945 -0.3048)
			(stroke
				(width 0.1)
				(type default)
			)
			(layer "F.Fab")
		)
		(fp_line
			(start 0.12065 -0.2794)
			(end 0.12065 -0.3048)
			(stroke
				(width 0.1)
				(type default)
			)
			(layer "F.Fab")
		)
		(fp_line
			(start 0.67945 -0.3048)
			(end 0.67945 0.3048)
			(stroke
				(width 0.1)
				(type default)
			)
			(layer "F.Fab")
		)
		(fp_line
			(start 0.67945 0.3048)
			(end 0.120396 0.3048)
			(stroke
				(width 0.1)
				(type default)
			)
			(layer "F.Fab")
		)
		(pad "1" smd circle
			(at -0.40005 0)
			(size 0 0)
			(layers "F.Cu" "F.Mask" "F.Paste")
			(net "HP_LVC3_OCP_V3_1_PWRGD")
		)
		(pad "2" smd circle
			(at 0.40005 0)
			(size 0 0)
			(layers "F.Cu" "F.Mask" "F.Paste")
			(net "HP_LVC3_OCP_V3_1_PWRGD_R")
		)
	)
)
